# S9S_MB_2U (Grand Teton) — schematic netlist excerpt (pin names and nets, part order shuffled) for the footprints in the layout excerpt that follows; sources: Cadence DE-HDL packaged netlist, KiCad conversion of 03242023_DA0F0TMBIJ0_F0T_Motherboard_J_brd_V01_OCP.brd

U316  74LVC2G17GW  IC  pkg SOT363  page 145
  A0  = SWB_HSC_EN
  GND  = GND
  A1  = GND
  B1  = NC_U316_2Y
  VCC  = P3V3_AUX
  B0  = SWB_HSC_EN_BUF_R

PR1783  Q_RES  3.3 1% CHIP  pkg 0402LF  page 272 : A = SW_PVCCFA_EHV_FIVRA_CPU0_BOOT4 ; B = SW_PVCCFA_EHV_FIVRA_CPU0_BOOT4_

(kicad_pcb
	(version 20260206)
	(generator "pcbnew")
	(generator_version "10.0")
	(general
		(thickness 1.6)
		(legacy_teardrops no)
	)
	(paper "A4")
	(title_block
		(title "03242023_DA0F0TMBIJ0_F0T_Motherboard_J_brd_V01_OCP.brd")
		(comment 1 "Grand Teton / footprints 1094-1095 of 6105")
	)
	(layers
		(0 "F.Cu" signal "TOP")
		(4 "In1.Cu" signal "GND")
		(6 "In2.Cu" signal "IN1")
		(8 "In3.Cu" signal "GND1")
		(10 "In4.Cu" signal "IN2")
		(12 "In5.Cu" signal "GND2")
		(14 "In6.Cu" signal "IN3")
		(16 "In7.Cu" signal "GND3")
		(18 "In8.Cu" signal "VCC")
		(20 "In9.Cu" signal "VCC1")
		(22 "In10.Cu" signal "GND4")
		(24 "In11.Cu" signal "IN4")
		(26 "In12.Cu" signal "GND5")
		(28 "In13.Cu" signal "IN5")
		(30 "In14.Cu" signal "GND6")
		(32 "In15.Cu" signal "IN6")
		(34 "In16.Cu" signal "GND7")
		(2 "B.Cu" signal "BOTTOM")
		(9 "F.Adhes" user "F.Adhesive")
		(11 "B.Adhes" user "B.Adhesive")
		(13 "F.Paste" user "Package Geometry/Pastemask Top")
		(15 "B.Paste" user "Package Geometry/Pastemask Bottom")
		(5 "F.SilkS" user "Ref Des/Silkscreen Top")
		(7 "B.SilkS" user "Ref Des/Silkscreen Bottom")
		(1 "F.Mask" user "Board Geometry/Soldermask Top")
		(3 "B.Mask" user "Board Geometry/Soldermask Bottom")
		(17 "Dwgs.User" user "User.Drawings")
		(19 "Cmts.User" user "User.Comments")
		(21 "Eco1.User" user "User.Eco1")
		(23 "Eco2.User" user "User.Eco2")
		(25 "Edge.Cuts" user "Board Geometry/Outline")
		(27 "Margin" user)
		(31 "F.CrtYd" user "Package Geometry/Place Bound Top")
		(29 "B.CrtYd" user "Package Geometry/Place Bound Bottom")
		(35 "F.Fab" user "Ref Des/Assembly Top")
		(33 "B.Fab" user "Ref Des/Assembly Bottom")
	)
	(footprint ""
		(layer "F.Cu")
		(at 289.545268 -367.378996 90)
		(property "Reference" "PR1783"
			(at 0 0 90)
			(layer "F.SilkS")
			(hide yes)
			(effects
				(font
					(size 1.27 1.27)
				)
			)
		)
		(property "Value" ""
			(at 0 0 90)
			(layer "F.Fab")
			(effects
				(font
					(size 1.27 1.27)
				)
			)
		)
		(duplicate_pad_numbers_are_jumpers no)
		(fp_line
			(start 0.7874 -0.4064)
			(end 0.7874 0.4064)
			(stroke
				(width 0.1524)
				(type default)
			)
			(layer "F.SilkS")
		)
		(fp_line
			(start -0.7874 -0.4064)
			(end 0.7874 -0.4064)
			(stroke
				(width 0.1524)
				(type default)
			)
			(layer "F.SilkS")
		)
		(fp_line
			(start 0.7874 0.4064)
			(end -0.7874 0.4064)
			(stroke
				(width 0.1524)
				(type default)
			)
			(layer "F.SilkS")
		)
		(fp_line
			(start -0.7874 0.4064)
			(end -0.7874 -0.4064)
			(stroke
				(width 0.1524)
				(type default)
			)
			(layer "F.SilkS")
		)
		(fp_line
			(start -0.12065 -0.305054)
			(end -0.12065 -0.2794)
			(stroke
				(width 0.1)
				(type default)
			)
			(layer "F.Fab")
		)
		(fp_line
			(start -0.67945 -0.305054)
			(end -0.12065 -0.305054)
			(stroke
				(width 0.1)
				(type default)
			)
			(layer "F.Fab")
		)
		(fp_line
			(start 0.67945 -0.3048)
			(end 0.67945 0.3048)
			(stroke
				(width 0.1)
				(type default)
			)
			(layer "F.Fab")
		)
		(fp_line
			(start 0.12065 -0.3048)
			(end 0.67945 -0.3048)
			(stroke
				(width 0.1)
				(type default)
			)
			(layer "F.Fab")
		)
		(fp_line
			(start 0.12065 -0.2794)
			(end 0.12065 -0.3048)
			(stroke
				(width 0.1)
				(type default)
			)
			(layer "F.Fab")
		)
		(fp_line
			(start -0.12065 -0.2794)
			(end 0.12065 -0.2794)
			(stroke
				(width 0.1)
				(type default)
			)
			(layer "F.Fab")
		)
		(fp_line
			(start 0.120396 0.2794)
			(end -0.12065 0.2794)
			(stroke
				(width 0.1)
				(type default)
			)
			(layer "F.Fab")
		)
		(fp_line
			(start -0.12065 0.2794)
			(end -0.12065 0.3048)
			(stroke
				(width 0.1)
				(type default)
			)
			(layer "F.Fab")
		)
		(fp_line
			(start 0.67945 0.3048)
			(end 0.120396 0.3048)
			(stroke
				(width 0.1)
				(type default)
			)
			(layer "F.Fab")
		)
		(fp_line
			(start 0.120396 0.3048)
			(end 0.120396 0.2794)
			(stroke
				(width 0.1)
				(type default)
			)
			(layer "F.Fab")
		)
		(fp_line
			(start -0.12065 0.3048)
			(end -0.67945 0.3048)
			(stroke
				(width 0.1)
				(type default)
			)
			(layer "F.Fab")
		)
		(fp_line
			(start -0.67945 0.3048)
			(end -0.67945 -0.305054)
			(stroke
				(width 0.1)
				(type default)
			)
			(layer "F.Fab")
		)
		(pad "1" smd circle
			(at -0.40005 0 90)
			(size 0 0)
			(layers "F.Cu" "F.Mask" "F.Paste")
			(net "SW_PVCCFA_EHV_FIVRA_CPU0_BOOT4")
		)
		(pad "2" smd circle
			(at 0.40005 0 90)
			(size 0 0)
			(layers "F.Cu" "F.Mask" "F.Paste")
			(net "SW_PVCCFA_EHV_FIVRA_CPU0_BOOT4_")
		)
	)
	(footprint ""
		(layer "F.Cu")
		(at 358.64546 -407.233628)
		(property "Reference" "U316"
			(at -2.84988 -2.53873 0)
			(unlocked yes)
			(layer "F.SilkS")
			(effects
				(font
					(size 0.7874 0.5842)
					(thickness 0.1524)
				)
				(justify left)
			)
		)
		(property "Value" ""
			(at 0 0 0)
			(layer "F.Fab")
			(effects
				(font
					(size 1.27 1.27)
				)
			)
		)
		(duplicate_pad_numbers_are_jumpers no)
		(fp_line
			(start -1.38176 -1.100074)
			(end -1.38176 1.100074)
			(stroke
				(width 0.1524)
				(type default)
			)
			(layer "F.SilkS")
		)
		(fp_line
			(start -1.38176 1.100074)
			(end 1.38176 1.100074)
			(stroke
				(width 0.1524)
				(type default)
			)
			(layer "F.SilkS")
		)
		(fp_line
			(start -0.592074 -1.100074)
			(end -1.38176 -1.100074)
			(stroke
				(width 0.1524)
				(type default)
			)
			(layer "F.SilkS")
		)
		(fp_line
			(start 0 -0.508)
			(end -0.592074 -1.100074)
			(stroke
				(width 0.1524)
				(type default)
			)
			(layer "F.SilkS")
		)
		(fp_line
			(start 0.592074 -1.100074)
			(end 0 -0.508)
			(stroke
				(width 0.1524)
				(type default)
			)
			(layer "F.SilkS")
		)
		(fp_line
			(start 1.38176 -1.100074)
			(end 0.592074 -1.100074)
			(stroke
				(width 0.1524)
				(type default)
			)
			(layer "F.SilkS")
		)
		(fp_line
			(start 1.38176 1.100074)
			(end 1.38176 -1.100074)
			(stroke
				(width 0.1524)
				(type default)
			)
			(layer "F.SilkS")
		)
		(fp_poly
			(pts
				(xy -1.50241 -0.649986) (xy -1.9431 -0.429768) (xy -1.9431 -0.870204)
			)
			(stroke
				(width 0)
				(type default)
			)
			(fill yes)
			(layer "F.SilkS")
		)
		(fp_line
			(start -1.100074 -0.8001)
			(end -0.670052 -0.8001)
			(stroke
				(width 0.1)
				(type default)
			)
			(layer "F.Fab")
		)
		(fp_line
			(start -1.100074 0.8001)
			(end -1.100074 -0.8001)
			(stroke
				(width 0.1)
				(type default)
			)
			(layer "F.Fab")
		)
		(fp_line
			(start -0.670052 -1.100074)
			(end 0.670052 -1.100074)
			(stroke
				(width 0.1)
				(type default)
			)
			(layer "F.Fab")
		)
		(fp_line
			(start -0.670052 -0.8001)
			(end -0.670052 -1.100074)
			(stroke
				(width 0.1)
				(type default)
			)
			(layer "F.Fab")
		)
		(fp_line
			(start -0.670052 0.8001)
			(end -1.100074 0.8001)
			(stroke
				(width 0.1)
				(type default)
			)
			(layer "F.Fab")
		)
		(fp_line
			(start -0.670052 0.8001)
			(end -0.670052 -0.8001)
			(stroke
				(width 0.1)
				(type default)
			)
			(layer "F.Fab")
		)
		(fp_line
			(start -0.670052 1.100074)
			(end -0.670052 0.8001)
			(stroke
				(width 0.1)
				(type default)
			)
			(layer "F.Fab")
		)
		(fp_line
			(start 0.670052 -1.100074)
			(end 0.670052 -0.8001)
			(stroke
				(width 0.1)
				(type default)
			)
			(layer "F.Fab")
		)
		(fp_line
			(start 0.670052 -0.8001)
			(end 0.670052 0.8001)
			(stroke
				(width 0.1)
				(type default)
			)
			(layer "F.Fab")
		)
		(fp_line
			(start 0.670052 -0.8001)
			(end 1.100074 -0.8001)
			(stroke
				(width 0.1)
				(type default)
			)
			(layer "F.Fab")
		)
		(fp_line
			(start 0.670052 0.8001)
			(end 0.670052 1.100074)
			(stroke
				(width 0.1)
				(type default)
			)
			(layer "F.Fab")
		)
		(fp_line
			(start 0.670052 1.100074)
			(end -0.670052 1.100074)
			(stroke
				(width 0.1)
				(type default)
			)
			(layer "F.Fab")
		)
		(fp_line
			(start 1.100074 -0.8001)
			(end 1.100074 0.8001)
			(stroke
				(width 0.1)
				(type default)
			)
			(layer "F.Fab")
		)
		(fp_line
			(start 1.100074 0.8001)
			(end 0.670052 0.8001)
			(stroke
				(width 0.1)
				(type default)
			)
			(layer "F.Fab")
		)
		(fp_poly
			(pts
				(xy -1.524 -0.649986) (xy -2.286 -1.030986) (xy -2.286 -0.268986)
			)
			(stroke
				(width 0)
				(type default)
			)
			(fill yes)
			(layer "F.Fab")
		)
		(pad "1" smd rect
			(at -0.94996 -0.649986 270)
			(size 0.4064 0.508)
			(layers "F.Cu" "F.Mask" "F.Paste")
			(net "SWB_HSC_EN")
		)
		(pad "2" smd rect
			(at -0.94996 0 270)
			(size 0.4064 0.508)
			(layers "F.Cu" "F.Mask" "F.Paste")
			(net "GND")
		)
		(pad "3" smd rect
			(at -0.94996 0.649986 270)
			(size 0.4064 0.508)
			(layers "F.Cu" "F.Mask" "F.Paste")
			(net "GND")
		)
		(pad "4" smd rect
			(at 0.94996 0.649986 270)
			(size 0.4064 0.508)
			(layers "F.Cu" "F.Mask" "F.Paste")
			(net "NC_U316_2Y")
		)
		(pad "5" smd rect
			(at 0.94996 0 270)
			(size 0.4064 0.508)
			(layers "F.Cu" "F.Mask" "F.Paste")
			(net "P3V3_AUX")
		)
		(pad "6" smd rect
			(at 0.94996 -0.649986 270)
			(size 0.4064 0.508)
			(layers "F.Cu" "F.Mask" "F.Paste")
			(net "SWB_HSC_EN_BUF_R")
		)
	)
)
